# BASEBOARD_FAB2 (Tioga Pass) — schematic netlist excerpt (pin names and nets, part order shuffled) for the footprints in the layout excerpt that follows; sources: Cadence DE-HDL packaged netlist, KiCad conversion of Wiwynn_Tioga_Pass_MB.brd

R25W57  RES  49.9K 1% CHIP  pkg 0402  page 147 : A = PD_ADCREXT ; B = GND
R4E16  RES  0.0 5% CHIP  pkg 0402  page 204 : A = VSENSE_PVCCIN_CPU0_P ; B = VSENSE_PVCCIN_CPU0_SKT_VSEN
C7A17  CAP  0.22UF 16V 10% X7R  pkg 0402  page 219 : A = P5V_STBY ; B = GND

(kicad_pcb
	(version 20260206)
	(generator "pcbnew")
	(generator_version "10.0")
	(general
		(thickness 1.6)
		(legacy_teardrops no)
	)
	(paper "A4")
	(title_block
		(title "Wiwynn_Tioga_Pass_MB.brd")
		(comment 1 "Tioga Pass / footprints 1729-1731 of 4770")
	)
	(layers
		(0 "F.Cu" signal "TOP")
		(4 "In1.Cu" signal "L2GND")
		(6 "In2.Cu" signal "L3")
		(8 "In3.Cu" signal "L4GND")
		(10 "In4.Cu" signal "L5")
		(12 "In5.Cu" signal "L6GND")
		(14 "In6.Cu" signal "L7VCC")
		(16 "In7.Cu" signal "L8VCC")
		(18 "In8.Cu" signal "L9GND")
		(20 "In9.Cu" signal "L10")
		(22 "In10.Cu" signal "L11GND")
		(24 "In11.Cu" signal "L12")
		(26 "In12.Cu" signal "L13GND")
		(2 "B.Cu" signal "BOTTOM")
		(9 "F.Adhes" user "F.Adhesive")
		(11 "B.Adhes" user "B.Adhesive")
		(13 "F.Paste" user "Package Geometry/Pastemask Top")
		(15 "B.Paste" user "Package Geometry/Pastemask Bottom")
		(5 "F.SilkS" user "Ref Des/Silkscreen Top")
		(7 "B.SilkS" user "Ref Des/Silkscreen Bottom")
		(1 "F.Mask" user "Board Geometry/Soldermask Top")
		(3 "B.Mask" user "Board Geometry/Soldermask Bottom")
		(17 "Dwgs.User" user "User.Drawings")
		(19 "Cmts.User" user "User.Comments")
		(21 "Eco1.User" user "User.Eco1")
		(23 "Eco2.User" user "User.Eco2")
		(25 "Edge.Cuts" user "Board Geometry/Outline")
		(27 "Margin" user)
		(31 "F.CrtYd" user "Package Geometry/Place Bound Top")
		(29 "B.CrtYd" user "Package Geometry/Place Bound Bottom")
		(35 "F.Fab" user "Ref Des/Assembly Top")
		(33 "B.Fab" user "Ref Des/Assembly Bottom")
	)
	(footprint ""
		(layer "F.Cu")
		(at 205.0288 -50.5714 90)
		(property "Reference" "R4E16"
			(at 0 0 90)
			(layer "F.SilkS")
			(hide yes)
			(effects
				(font
					(size 1.27 1.27)
				)
			)
		)
		(property "Value" ""
			(at 0 0 90)
			(layer "F.Fab")
			(effects
				(font
					(size 1.27 1.27)
				)
			)
		)
		(duplicate_pad_numbers_are_jumpers no)
		(fp_poly
			(pts
				(xy -0.2794 -0.1016) (xy 0.2794 -0.1016) (xy 0.2794 0.9906) (xy -0.2794 0.9906)
			)
			(stroke
				(width 0)
				(type default)
			)
			(fill no)
			(layer "F.CrtYd")
		)
		(fp_line
			(start 0.2794 -0.1016)
			(end -0.2794 -0.1016)
			(stroke
				(width 0.1)
				(type default)
			)
			(layer "F.Fab")
		)
		(fp_line
			(start -0.2794 -0.1016)
			(end -0.2794 0.9906)
			(stroke
				(width 0.1)
				(type default)
			)
			(layer "F.Fab")
		)
		(fp_line
			(start 0.2794 0.9906)
			(end 0.2794 -0.1016)
			(stroke
				(width 0.1)
				(type default)
			)
			(layer "F.Fab")
		)
		(fp_line
			(start -0.2794 0.9906)
			(end 0.2794 0.9906)
			(stroke
				(width 0.1)
				(type default)
			)
			(layer "F.Fab")
		)
		(pad "1" smd rect
			(at 0 0 90)
			(size 0.508 0.508)
			(layers "F.Cu" "F.Mask" "F.Paste")
			(net "VSENSE_PVCCIN_CPU0_P")
		)
		(pad "2" smd rect
			(at 0 0.889 90)
			(size 0.508 0.508)
			(layers "F.Cu" "F.Mask" "F.Paste")
			(net "VSENSE_PVCCIN_CPU0_SKT_VSEN")
		)
		(zone
			(layer "F.Cu")
			(hatch none 0.5)
			(connect_pads
				(clearance 0)
			)
			(min_thickness 0.25)
			(keepout
				(tracks allowed)
				(vias not_allowed)
				(pads allowed)
				(copperpour not_allowed)
				(footprints allowed)
			)
			(placement
				(enabled no)
				(sheetname "")
			)
			(fill
				(thermal_gap 0.5)
				(thermal_bridge_width 0.5)
				(island_removal_mode 0)
			)
			(polygon
				(pts
					(xy 205.2828 -50.3174) (xy 205.2828 -50.8254) (xy 205.6638 -50.8254) (xy 205.6638 -50.3174)
				)
			)
		)
		(zone
			(layer "F.Cu")
			(hatch none 0.5)
			(connect_pads
				(clearance 0)
			)
			(min_thickness 0.25)
			(keepout
				(tracks not_allowed)
				(vias allowed)
				(pads allowed)
				(copperpour not_allowed)
				(footprints allowed)
			)
			(placement
				(enabled no)
				(sheetname "")
			)
			(fill
				(thermal_gap 0.5)
				(thermal_bridge_width 0.5)
				(island_removal_mode 0)
			)
			(polygon
				(pts
					(xy 205.6638 -50.3174) (xy 205.6638 -50.8254) (xy 205.2828 -50.8254) (xy 205.2828 -50.3174)
				)
			)
		)
	)
	(footprint ""
		(layer "F.Cu")
		(at 348.4118 -157.2768 -90)
		(property "Reference" "C7A17"
			(at 0 0 270)
			(layer "F.SilkS")
			(hide yes)
			(effects
				(font
					(size 1.27 1.27)
				)
			)
		)
		(property "Value" ""
			(at 0 0 270)
			(layer "F.Fab")
			(effects
				(font
					(size 1.27 1.27)
				)
			)
		)
		(duplicate_pad_numbers_are_jumpers no)
		(fp_poly
			(pts
				(xy 0.3048 -0.1016) (xy 0.3048 0.9906) (xy -0.3048 0.9906) (xy -0.3048 -0.1016)
			)
			(stroke
				(width 0)
				(type default)
			)
			(fill no)
			(layer "F.CrtYd")
		)
		(fp_line
			(start -0.3048 0.9906)
			(end 0.3048 0.9906)
			(stroke
				(width 0.1)
				(type default)
			)
			(layer "F.Fab")
		)
		(fp_line
			(start 0.3048 0.9906)
			(end 0.3048 -0.1016)
			(stroke
				(width 0.1)
				(type default)
			)
			(layer "F.Fab")
		)
		(fp_line
			(start -0.3048 -0.1016)
			(end -0.3048 0.9906)
			(stroke
				(width 0.1)
				(type default)
			)
			(layer "F.Fab")
		)
		(fp_line
			(start 0.3048 -0.1016)
			(end -0.3048 -0.1016)
			(stroke
				(width 0.1)
				(type default)
			)
			(layer "F.Fab")
		)
		(pad "1" smd rect
			(at 0 0 270)
			(size 0.508 0.508)
			(layers "F.Cu" "F.Mask" "F.Paste")
			(net "P5V_STBY")
		)
		(pad "2" smd rect
			(at 0 0.889 270)
			(size 0.508 0.508)
			(layers "F.Cu" "F.Mask" "F.Paste")
			(net "GND")
		)
		(zone
			(layer "F.Cu")
			(hatch none 0.5)
			(connect_pads
				(clearance 0)
			)
			(min_thickness 0.25)
			(keepout
				(tracks not_allowed)
				(vias allowed)
				(pads allowed)
				(copperpour not_allowed)
				(footprints allowed)
			)
			(placement
				(enabled no)
				(sheetname "")
			)
			(fill
				(thermal_gap 0.5)
				(thermal_bridge_width 0.5)
				(island_removal_mode 0)
			)
			(polygon
				(pts
					(xy 347.7768 -157.5308) (xy 347.7768 -157.0228) (xy 348.1578 -157.0228) (xy 348.1578 -157.5308)
				)
			)
		)
		(zone
			(layer "F.Cu")
			(hatch none 0.5)
			(connect_pads
				(clearance 0)
			)
			(min_thickness 0.25)
			(keepout
				(tracks allowed)
				(vias not_allowed)
				(pads allowed)
				(copperpour not_allowed)
				(footprints allowed)
			)
			(placement
				(enabled no)
				(sheetname "")
			)
			(fill
				(thermal_gap 0.5)
				(thermal_bridge_width 0.5)
				(island_removal_mode 0)
			)
			(polygon
				(pts
					(xy 348.1578 -157.5308) (xy 348.1578 -157.0228) (xy 347.7768 -157.0228) (xy 347.7768 -157.5308)
				)
			)
		)
	)
	(footprint ""
		(layer "F.Cu")
		(at 412.877 -22.9235)
		(property "Reference" "R25W57"
			(at -0.8382 -0.67818 0)
			(unlocked yes)
			(layer "F.SilkS")
			(effects
				(font
					(size 0.4064 0.254)
					(thickness 0.1524)
				)
				(justify left)
			)
		)
		(property "Value" ""
			(at 0 0 0)
			(layer "F.Fab")
			(effects
				(font
					(size 1.27 1.27)
				)
			)
		)
		(duplicate_pad_numbers_are_jumpers no)
		(fp_poly
			(pts
				(xy -0.2794 -0.1016) (xy 0.2794 -0.1016) (xy 0.2794 0.9906) (xy -0.2794 0.9906)
			)
			(stroke
				(width 0)
				(type default)
			)
			(fill no)
			(layer "F.CrtYd")
		)
		(fp_line
			(start -0.2794 -0.1016)
			(end -0.2794 0.9906)
			(stroke
				(width 0.1)
				(type default)
			)
			(layer "F.Fab")
		)
		(fp_line
			(start -0.2794 0.9906)
			(end 0.2794 0.9906)
			(stroke
				(width 0.1)
				(type default)
			)
			(layer "F.Fab")
		)
		(fp_line
			(start 0.2794 -0.1016)
			(end -0.2794 -0.1016)
			(stroke
				(width 0.1)
				(type default)
			)
			(layer "F.Fab")
		)
		(fp_line
			(start 0.2794 0.9906)
			(end 0.2794 -0.1016)
			(stroke
				(width 0.1)
				(type default)
			)
			(layer "F.Fab")
		)
		(pad "1" smd rect
			(at 0 0)
			(size 0.508 0.508)
			(layers "F.Cu" "F.Mask" "F.Paste")
			(net "PD_ADCREXT")
		)
		(pad "2" smd rect
			(at 0 0.889)
			(size 0.508 0.508)
			(layers "F.Cu" "F.Mask" "F.Paste")
			(net "GND")
		)
		(zone
			(layer "F.Cu")
			(hatch none 0.5)
			(connect_pads
				(clearance 0)
			)
			(min_thickness 0.25)
			(keepout
				(tracks allowed)
				(vias not_allowed)
				(pads allowed)
				(copperpour not_allowed)
				(footprints allowed)
			)
			(placement
				(enabled no)
				(sheetname "")
			)
			(fill
				(thermal_gap 0.5)
				(thermal_bridge_width 0.5)
				(island_removal_mode 0)
			)
			(polygon
				(pts
					(xy 412.623 -22.6695) (xy 413.131 -22.6695) (xy 413.131 -22.2885) (xy 412.623 -22.2885)
				)
			)
		)
		(zone
			(layer "F.Cu")
			(hatch none 0.5)
			(connect_pads
				(clearance 0)
			)
			(min_thickness 0.25)
			(keepout
				(tracks not_allowed)
				(vias allowed)
				(pads allowed)
				(copperpour not_allowed)
				(footprints allowed)
			)
			(placement
				(enabled no)
				(sheetname "")
			)
			(fill
				(thermal_gap 0.5)
				(thermal_bridge_width 0.5)
				(island_removal_mode 0)
			)
			(polygon
				(pts
					(xy 412.623 -22.2885) (xy 413.131 -22.2885) (xy 413.131 -22.6695) (xy 412.623 -22.6695)
				)
			)
		)
	)
)
